(kicad_pcb
	(version 20241229)
	(generator "pcbnew")
	(generator_version "9.0")
	(general
		(thickness 1.61)
		(legacy_teardrops no)
	)
	(paper "A3")
	(title_block
		(title "SO-DIMM DDR5 Tester")
		(date "2025-11-26")
		(rev "1.3.0")
		(comment 9 "footprints 319-323 of 627")
	)
	(layers
		(0 "F.Cu" signal)
		(4 "In1.Cu" power)
		(6 "In2.Cu" mixed)
		(8 "In3.Cu" power)
		(10 "In4.Cu" mixed)
		(12 "In5.Cu" power)
		(14 "In6.Cu" mixed)
		(16 "In7.Cu" power)
		(18 "In8.Cu" power)
		(20 "In9.Cu" mixed)
		(22 "In10.Cu" power)
		(2 "B.Cu" signal)
		(9 "F.Adhes" user "F.Adhesive")
		(11 "B.Adhes" user "B.Adhesive")
		(13 "F.Paste" user)
		(15 "B.Paste" user)
		(5 "F.SilkS" user "F.Silkscreen")
		(7 "B.SilkS" user "B.Silkscreen")
		(1 "F.Mask" user)
		(3 "B.Mask" user)
		(17 "Dwgs.User" user "User.Drawings")
		(19 "Cmts.User" user "User.Comments")
		(21 "Eco1.User" user "User.Eco1")
		(23 "Eco2.User" user "User.Eco2")
		(25 "Edge.Cuts" user)
		(27 "Margin" user)
		(31 "F.CrtYd" user "F.Courtyard")
		(29 "B.CrtYd" user "B.Courtyard")
		(35 "F.Fab" user)
		(33 "B.Fab" user)
	)
	(footprint "antmicro-footprints:PinHeader_2x7_P2mm_SMD_Shrouded_no-locator"
		(layer "F.Cu")
		(at 170.8 174.4 90)
		(descr "Pin Header 2x7 SMD Shrouded no-locator")
		(property "Reference" "J1"
			(at -9.7 2.3 180)
			(layer "F.SilkS")
			(effects
				(font
					(size 0.7 0.7)
					(thickness 0.15)
				)
				(justify left bottom)
			)
		)
		(property "Value" "PinHeader_2x7_P2mm_SMD_Shrouded_no-locator"
			(at 0 5.038 90)
			(layer "F.Fab")
			(effects
				(font
					(size 0.7 0.7)
					(thickness 0.15)
				)
				(justify left bottom)
			)
		)
		(property "Datasheet" "https://www.molex.com/pdm_docs/ps/PS-87831-027-001.pdf"
			(at 0 0 90)
			(layer "F.Fab")
			(hide yes)
			(effects
				(font
					(size 1.27 1.27)
					(thickness 0.15)
				)
			)
		)
		(property "Author" "Antmicro"
			(at 345.2 3.6 0)
			(layer "F.Fab")
			(hide yes)
			(effects
				(font
					(size 1 1)
					(thickness 0.15)
				)
			)
		)
		(property "License" "Apache-2.0"
			(at 345.2 3.6 0)
			(layer "F.Fab")
			(hide yes)
			(effects
				(font
					(size 1 1)
					(thickness 0.15)
				)
			)
		)
		(property "MPN" "878321412"
			(at 345.2 3.6 0)
			(layer "F.Fab")
			(hide yes)
			(effects
				(font
					(size 1 1)
					(thickness 0.15)
				)
			)
		)
		(property "Manufacturer" "Molex"
			(at 345.2 3.6 0)
			(layer "F.Fab")
			(hide yes)
			(effects
				(font
					(size 1 1)
					(thickness 0.15)
				)
			)
		)
		(sheetname "/FPGA Config/")
		(sheetfile "fpga-config.kicad_sch")
		(attr exclude_from_pos_files exclude_from_bom dnp)
		(fp_line
			(start 8.499 -3.301)
			(end 7.998 -3.301)
			(stroke
				(width 0.15)
				(type solid)
			)
			(layer "F.SilkS")
		)
		(fp_line
			(start 8.499 -3.301)
			(end 8.499 -2.801)
			(stroke
				(width 0.15)
				(type solid)
			)
			(layer "F.SilkS")
		)
		(fp_line
			(start -8.5 -3.301)
			(end -8 -3.301)
			(stroke
				(width 0.15)
				(type solid)
			)
			(layer "F.SilkS")
		)
		(fp_line
			(start -8.5 -3.301)
			(end -8.5 -2.801)
			(stroke
				(width 0.15)
				(type solid)
			)
			(layer "F.SilkS")
		)
		(fp_line
			(start -1.397 2.41)
			(end -0.9 2.41)
			(stroke
				(width 0.15)
				(type solid)
			)
			(layer "F.SilkS")
		)
		(fp_line
			(start -1.397 2.41)
			(end -1.397 2.91)
			(stroke
				(width 0.15)
				(type solid)
			)
			(layer "F.SilkS")
		)
		(fp_line
			(start 1.394 2.418)
			(end 0.897 2.418)
			(stroke
				(width 0.15)
				(type solid)
			)
			(layer "F.SilkS")
		)
		(fp_line
			(start 1.394 2.418)
			(end 1.394 2.918)
			(stroke
				(width 0.15)
				(type solid)
			)
			(layer "F.SilkS")
		)
		(fp_line
			(start 8.499 3.297)
			(end 8.499 2.797)
			(stroke
				(width 0.15)
				(type solid)
			)
			(layer "F.SilkS")
		)
		(fp_line
			(start 8.499 3.297)
			(end 7.998 3.297)
			(stroke
				(width 0.15)
				(type solid)
			)
			(layer "F.SilkS")
		)
		(fp_line
			(start -8.5 3.297)
			(end -8.5 2.797)
			(stroke
				(width 0.15)
				(type solid)
			)
			(layer "F.SilkS")
		)
		(fp_line
			(start -8.5 3.297)
			(end -8 3.297)
			(stroke
				(width 0.15)
				(type solid)
			)
			(layer "F.SilkS")
		)
		(fp_circle
			(center -6.8 3.4)
			(end -6.748 3.4)
			(stroke
				(width 0.15)
				(type solid)
			)
			(fill yes)
			(layer "F.SilkS")
		)
		(fp_rect
			(start -8.7 -3.7)
			(end 8.7 3.7)
			(stroke
				(width 0.05)
				(type solid)
			)
			(fill no)
			(layer "F.CrtYd")
		)
		(fp_line
			(start -8.325 -3.15)
			(end 8.323 -3.15)
			(stroke
				(width 0.15)
				(type solid)
			)
			(layer "F.Fab")
		)
		(fp_line
			(start 1.394 2.41)
			(end 1.394 3.14)
			(stroke
				(width 0.15)
				(type solid)
			)
			(layer "F.Fab")
		)
		(fp_line
			(start -1.397 2.41)
			(end 1.394 2.41)
			(stroke
				(width 0.15)
				(type solid)
			)
			(layer "F.Fab")
		)
		(fp_line
			(start -1.397 2.41)
			(end -1.397 3.14)
			(stroke
				(width 0.15)
				(type solid)
			)
			(layer "F.Fab")
		)
		(fp_line
			(start 8.323 3.148)
			(end 8.323 -3.15)
			(stroke
				(width 0.15)
				(type solid)
			)
			(layer "F.Fab")
		)
		(fp_line
			(start 1.394 3.148)
			(end 8.323 3.148)
			(stroke
				(width 0.15)
				(type solid)
			)
			(layer "F.Fab")
		)
		(fp_line
			(start -8.325 3.148)
			(end -8.325 -3.15)
			(stroke
				(width 0.15)
				(type solid)
			)
			(layer "F.Fab")
		)
		(fp_line
			(start -8.325 3.148)
			(end -1.397 3.148)
			(stroke
				(width 0.15)
				(type solid)
			)
			(layer "F.Fab")
		)
		(pad "1" smd rect
			(at -6 2.128 90)
			(size 1 2.75)
			(layers "F.Cu" "F.Mask" "F.Paste")
			(net 1 "GND")
			(pintype "passive")
		)
		(pad "2" smd rect
			(at -6 -2.13 90)
			(size 1 2.75)
			(layers "F.Cu" "F.Mask" "F.Paste")
			(net 200 "+3V3")
			(pintype "passive")
		)
		(pad "3" smd rect
			(at -4 2.128 90)
			(size 1 2.75)
			(layers "F.Cu" "F.Mask" "F.Paste")
			(net 1 "GND")
			(pintype "passive")
		)
		(pad "4" smd rect
			(at -4 -2.13 90)
			(size 1 2.75)
			(layers "F.Cu" "F.Mask" "F.Paste")
			(net 45 "/Debug FTDI/JTAG.TMS")
			(pintype "passive")
		)
		(pad "5" smd rect
			(at -2 2.128 90)
			(size 1 2.75)
			(layers "F.Cu" "F.Mask" "F.Paste")
			(net 1 "GND")
			(pintype "passive")
		)
		(pad "6" smd rect
			(at -2 -2.13 90)
			(size 1 2.75)
			(layers "F.Cu" "F.Mask" "F.Paste")
			(net 46 "/Debug FTDI/JTAG.TCK")
			(pintype "passive")
		)
		(pad "7" smd rect
			(at 0 2.128 90)
			(size 1 2.75)
			(layers "F.Cu" "F.Mask" "F.Paste")
			(net 1 "GND")
			(pintype "passive")
		)
		(pad "8" smd rect
			(at 0 -2.13 90)
			(size 1 2.75)
			(layers "F.Cu" "F.Mask" "F.Paste")
			(net 47 "/Debug FTDI/JTAG.TDO")
			(pintype "passive")
		)
		(pad "9" smd rect
			(at 1.999 2.128 90)
			(size 1 2.75)
			(layers "F.Cu" "F.Mask" "F.Paste")
			(net 1 "GND")
			(pintype "passive")
		)
		(pad "10" smd rect
			(at 1.999 -2.13 90)
			(size 1 2.75)
			(layers "F.Cu" "F.Mask" "F.Paste")
			(net 48 "/Debug FTDI/JTAG.TDI")
			(pintype "passive")
		)
		(pad "11" smd rect
			(at 3.999 2.128 90)
			(size 1 2.75)
			(layers "F.Cu" "F.Mask" "F.Paste")
			(net 1 "GND")
			(pintype "passive")
		)
		(pad "12" smd rect
			(at 3.999 -2.13 90)
			(size 1 2.75)
			(layers "F.Cu" "F.Mask" "F.Paste")
			(net 319 "unconnected-(J1-Pad12)")
			(pintype "passive+no_connect")
		)
		(pad "13" smd rect
			(at 5.998 2.128 90)
			(size 1 2.75)
			(layers "F.Cu" "F.Mask" "F.Paste")
			(net 1 "GND")
			(pintype "passive")
		)
		(pad "14" smd rect
			(at 5.998 -2.13 90)
			(size 1 2.75)
			(layers "F.Cu" "F.Mask" "F.Paste")
			(net 320 "unconnected-(J1-Pad14)")
			(pintype "passive+no_connect")
		)
	)
	(footprint "antmicro-footprints:R_0402_1005Metric"
		(layer "B.Cu")
		(at 98 180.95 -90)
		(descr "Resistor SMD 0402")
		(tags "resistor SMD 0402")
		(property "Reference" "R56"
			(at -1.122484 0.772697 90)
			(layer "B.SilkS")
			(hide yes)
			(effects
				(font
					(size 0.7 0.7)
					(thickness 0.15)
				)
				(justify left bottom mirror)
			)
		)
		(property "Value" "R_22R_0402"
			(at -1.011843 -1.772047 90)
			(layer "B.Fab")
			(effects
				(font
					(size 0.7 0.7)
					(thickness 0.15)
				)
				(justify left bottom mirror)
			)
		)
		(property "Datasheet" "https://www.bourns.com/docs/product-datasheets/cr.pdf"
			(at 0 0 270)
			(layer "F.Fab")
			(hide yes)
			(effects
				(font
					(size 1.27 1.27)
					(thickness 0.15)
				)
			)
		)
		(property "Author" "Antmicro"
			(at -82.95 278.95 0)
			(layer "B.Fab")
			(hide yes)
			(effects
				(font
					(size 1 1)
					(thickness 0.15)
				)
				(justify mirror)
			)
		)
		(property "License" "Apache-2.0"
			(at -82.95 278.95 0)
			(layer "B.Fab")
			(hide yes)
			(effects
				(font
					(size 1 1)
					(thickness 0.15)
				)
				(justify mirror)
			)
		)
		(property "MPN" "CR0402-FX-22R0GLF"
			(at -82.95 278.95 0)
			(layer "B.Fab")
			(hide yes)
			(effects
				(font
					(size 1 1)
					(thickness 0.15)
				)
				(justify mirror)
			)
		)
		(property "Manufacturer" "Bourns"
			(at -82.95 278.95 0)
			(layer "B.Fab")
			(hide yes)
			(effects
				(font
					(size 1 1)
					(thickness 0.15)
				)
				(justify mirror)
			)
		)
		(property "Tolerance" "1%"
			(at -82.95 278.95 0)
			(layer "B.Fab")
			(hide yes)
			(effects
				(font
					(size 1 1)
					(thickness 0.15)
				)
				(justify mirror)
			)
		)
		(property "Val" "22R"
			(at -82.95 278.95 0)
			(layer "B.Fab")
			(hide yes)
			(effects
				(font
					(size 1 1)
					(thickness 0.15)
				)
				(justify mirror)
			)
		)
		(sheetname "/Debug FTDI/")
		(sheetfile "debug-ftdi.kicad_sch")
		(attr exclude_from_pos_files exclude_from_bom dnp)
		(fp_rect
			(start -0.93 0.47)
			(end 0.93 -0.47)
			(stroke
				(width 0.05)
				(type solid)
			)
			(fill no)
			(layer "B.CrtYd")
		)
		(fp_rect
			(start -0.5 0.25)
			(end 0.5 -0.25)
			(stroke
				(width 0.15)
				(type solid)
			)
			(fill no)
			(layer "B.Fab")
		)
		(pad "1" smd roundrect
			(at -0.485 0 270)
			(size 0.59 0.64)
			(layers "B.Cu" "B.Mask" "B.Paste")
			(roundrect_rratio 0.25)
			(net 646 "/Debug FTDI/BDBUS0")
			(pintype "passive")
		)
		(pad "2" smd roundrect
			(at 0.485 0 270)
			(size 0.59 0.64)
			(layers "B.Cu" "B.Mask" "B.Paste")
			(roundrect_rratio 0.25)
			(net 647 "/Debug FTDI/AUX.TCK")
			(pintype "passive")
		)
	)
	(footprint "antmicro-footprints:R_0402_1005Metric"
		(layer "B.Cu")
		(at 99.05 180.95 -90)
		(descr "Resistor SMD 0402")
		(tags "resistor SMD 0402")
		(property "Reference" "R57"
			(at -1.122484 0.772697 90)
			(layer "B.SilkS")
			(hide yes)
			(effects
				(font
					(size 0.7 0.7)
					(thickness 0.15)
				)
				(justify left bottom mirror)
			)
		)
		(property "Value" "R_22R_0402"
			(at -1.011843 -1.772047 90)
			(layer "B.Fab")
			(effects
				(font
					(size 0.7 0.7)
					(thickness 0.15)
				)
				(justify left bottom mirror)
			)
		)
		(property "Datasheet" "https://www.bourns.com/docs/product-datasheets/cr.pdf"
			(at 0 0 270)
			(layer "F.Fab")
			(hide yes)
			(effects
				(font
					(size 1.27 1.27)
					(thickness 0.15)
				)
			)
		)
		(property "Author" "Antmicro"
			(at -81.9 280 0)
			(layer "B.Fab")
			(hide yes)
			(effects
				(font
					(size 1 1)
					(thickness 0.15)
				)
				(justify mirror)
			)
		)
		(property "License" "Apache-2.0"
			(at -81.9 280 0)
			(layer "B.Fab")
			(hide yes)
			(effects
				(font
					(size 1 1)
					(thickness 0.15)
				)
				(justify mirror)
			)
		)
		(property "MPN" "CR0402-FX-22R0GLF"
			(at -81.9 280 0)
			(layer "B.Fab")
			(hide yes)
			(effects
				(font
					(size 1 1)
					(thickness 0.15)
				)
				(justify mirror)
			)
		)
		(property "Manufacturer" "Bourns"
			(at -81.9 280 0)
			(layer "B.Fab")
			(hide yes)
			(effects
				(font
					(size 1 1)
					(thickness 0.15)
				)
				(justify mirror)
			)
		)
		(property "Tolerance" "1%"
			(at -81.9 280 0)
			(layer "B.Fab")
			(hide yes)
			(effects
				(font
					(size 1 1)
					(thickness 0.15)
				)
				(justify mirror)
			)
		)
		(property "Val" "22R"
			(at -81.9 280 0)
			(layer "B.Fab")
			(hide yes)
			(effects
				(font
					(size 1 1)
					(thickness 0.15)
				)
				(justify mirror)
			)
		)
		(sheetname "/Debug FTDI/")
		(sheetfile "debug-ftdi.kicad_sch")
		(attr exclude_from_pos_files exclude_from_bom dnp)
		(fp_rect
			(start -0.93 0.47)
			(end 0.93 -0.47)
			(stroke
				(width 0.05)
				(type solid)
			)
			(fill no)
			(layer "B.CrtYd")
		)
		(fp_rect
			(start -0.5 0.25)
			(end 0.5 -0.25)
			(stroke
				(width 0.15)
				(type solid)
			)
			(fill no)
			(layer "B.Fab")
		)
		(pad "1" smd roundrect
			(at -0.485 0 270)
			(size 0.59 0.64)
			(layers "B.Cu" "B.Mask" "B.Paste")
			(roundrect_rratio 0.25)
			(net 648 "/Debug FTDI/BDBUS1")
			(pintype "passive")
		)
		(pad "2" smd roundrect
			(at 0.485 0 270)
			(size 0.59 0.64)
			(layers "B.Cu" "B.Mask" "B.Paste")
			(roundrect_rratio 0.25)
			(net 649 "/Debug FTDI/AUX.TDI")
			(pintype "passive")
		)
	)
	(footprint "antmicro-footprints:R_0402_1005Metric"
		(layer "B.Cu")
		(at 100.1 180.95 -90)
		(descr "Resistor SMD 0402")
		(tags "resistor SMD 0402")
		(property "Reference" "R58"
			(at -1.122484 0.772697 90)
			(layer "B.SilkS")
			(hide yes)
			(effects
				(font
					(size 0.7 0.7)
					(thickness 0.15)
				)
				(justify left bottom mirror)
			)
		)
		(property "Value" "R_22R_0402"
			(at -1.011843 -1.772047 90)
			(layer "B.Fab")
			(effects
				(font
					(size 0.7 0.7)
					(thickness 0.15)
				)
				(justify left bottom mirror)
			)
		)
		(property "Datasheet" "https://www.bourns.com/docs/product-datasheets/cr.pdf"
			(at 0 0 270)
			(layer "F.Fab")
			(hide yes)
			(effects
				(font
					(size 1.27 1.27)
					(thickness 0.15)
				)
			)
		)
		(property "Author" "Antmicro"
			(at -80.85 281.05 0)
			(layer "B.Fab")
			(hide yes)
			(effects
				(font
					(size 1 1)
					(thickness 0.15)
				)
				(justify mirror)
			)
		)
		(property "License" "Apache-2.0"
			(at -80.85 281.05 0)
			(layer "B.Fab")
			(hide yes)
			(effects
				(font
					(size 1 1)
					(thickness 0.15)
				)
				(justify mirror)
			)
		)
		(property "MPN" "CR0402-FX-22R0GLF"
			(at -80.85 281.05 0)
			(layer "B.Fab")
			(hide yes)
			(effects
				(font
					(size 1 1)
					(thickness 0.15)
				)
				(justify mirror)
			)
		)
		(property "Manufacturer" "Bourns"
			(at -80.85 281.05 0)
			(layer "B.Fab")
			(hide yes)
			(effects
				(font
					(size 1 1)
					(thickness 0.15)
				)
				(justify mirror)
			)
		)
		(property "Tolerance" "1%"
			(at -80.85 281.05 0)
			(layer "B.Fab")
			(hide yes)
			(effects
				(font
					(size 1 1)
					(thickness 0.15)
				)
				(justify mirror)
			)
		)
		(property "Val" "22R"
			(at -80.85 281.05 0)
			(layer "B.Fab")
			(hide yes)
			(effects
				(font
					(size 1 1)
					(thickness 0.15)
				)
				(justify mirror)
			)
		)
		(sheetname "/Debug FTDI/")
		(sheetfile "debug-ftdi.kicad_sch")
		(attr exclude_from_pos_files exclude_from_bom dnp)
		(fp_rect
			(start -0.93 0.47)
			(end 0.93 -0.47)
			(stroke
				(width 0.05)
				(type solid)
			)
			(fill no)
			(layer "B.CrtYd")
		)
		(fp_rect
			(start -0.5 0.25)
			(end 0.5 -0.25)
			(stroke
				(width 0.15)
				(type solid)
			)
			(fill no)
			(layer "B.Fab")
		)
		(pad "1" smd roundrect
			(at -0.485 0 270)
			(size 0.59 0.64)
			(layers "B.Cu" "B.Mask" "B.Paste")
			(roundrect_rratio 0.25)
			(net 650 "/Debug FTDI/BDBUS2")
			(pintype "passive")
		)
		(pad "2" smd roundrect
			(at 0.485 0 270)
			(size 0.59 0.64)
			(layers "B.Cu" "B.Mask" "B.Paste")
			(roundrect_rratio 0.25)
			(net 651 "/Debug FTDI/AUX.TDO")
			(pintype "passive")
		)
	)
	(footprint "antmicro-footprints:R_0402_1005Metric"
		(layer "B.Cu")
		(at 102.2 180.95 -90)
		(descr "Resistor SMD 0402")
		(tags "resistor SMD 0402")
		(property "Reference" "R60"
			(at -1.122484 0.772697 90)
			(layer "B.SilkS")
			(hide yes)
			(effects
				(font
					(size 0.7 0.7)
					(thickness 0.15)
				)
				(justify left bottom mirror)
			)
		)
		(property "Value" "R_22R_0402"
			(at -1.011843 -1.772047 90)
			(layer "B.Fab")
			(effects
				(font
					(size 0.7 0.7)
					(thickness 0.15)
				)
				(justify left bottom mirror)
			)
		)
		(property "Datasheet" "https://www.bourns.com/docs/product-datasheets/cr.pdf"
			(at 0 0 270)
			(layer "F.Fab")
			(hide yes)
			(effects
				(font
					(size 1.27 1.27)
					(thickness 0.15)
				)
			)
		)
		(property "Author" "Antmicro"
			(at -78.75 283.15 0)
			(layer "B.Fab")
			(hide yes)
			(effects
				(font
					(size 1 1)
					(thickness 0.15)
				)
				(justify mirror)
			)
		)
		(property "License" "Apache-2.0"
			(at -78.75 283.15 0)
			(layer "B.Fab")
			(hide yes)
			(effects
				(font
					(size 1 1)
					(thickness 0.15)
				)
				(justify mirror)
			)
		)
		(property "MPN" "CR0402-FX-22R0GLF"
			(at -78.75 283.15 0)
			(layer "B.Fab")
			(hide yes)
			(effects
				(font
					(size 1 1)
					(thickness 0.15)
				)
				(justify mirror)
			)
		)
		(property "Manufacturer" "Bourns"
			(at -78.75 283.15 0)
			(layer "B.Fab")
			(hide yes)
			(effects
				(font
					(size 1 1)
					(thickness 0.15)
				)
				(justify mirror)
			)
		)
		(property "Tolerance" "1%"
			(at -78.75 283.15 0)
			(layer "B.Fab")
			(hide yes)
			(effects
				(font
					(size 1 1)
					(thickness 0.15)
				)
				(justify mirror)
			)
		)
		(property "Val" "22R"
			(at -78.75 283.15 0)
			(layer "B.Fab")
			(hide yes)
			(effects
				(font
					(size 1 1)
					(thickness 0.15)
				)
				(justify mirror)
			)
		)
		(sheetname "/Debug FTDI/")
		(sheetfile "debug-ftdi.kicad_sch")
		(attr exclude_from_pos_files exclude_from_bom dnp)
		(fp_rect
			(start -0.93 0.47)
			(end 0.93 -0.47)
			(stroke
				(width 0.05)
				(type solid)
			)
			(fill no)
			(layer "B.CrtYd")
		)
		(fp_rect
			(start -0.5 0.25)
			(end 0.5 -0.25)
			(stroke
				(width 0.15)
				(type solid)
			)
			(fill no)
			(layer "B.Fab")
		)
		(pad "1" smd roundrect
			(at -0.485 0 270)
			(size 0.59 0.64)
			(layers "B.Cu" "B.Mask" "B.Paste")
			(roundrect_rratio 0.25)
			(net 654 "/Debug FTDI/I2C_EN")
			(pintype "passive")
		)
		(pad "2" smd roundrect
			(at 0.485 0 270)
			(size 0.59 0.64)
			(layers "B.Cu" "B.Mask" "B.Paste")
			(roundrect_rratio 0.25)
			(net 655 "/Debug FTDI/AUX.RST")
			(pintype "passive")
		)
	)
)
